(kicad_pcb
	(version 20241229)
	(generator "pcbnew")
	(generator_version "9.0")
	(general
		(thickness 1.61)
		(legacy_teardrops no)
	)
	(paper "A3")
	(title_block
		(title "RDIMM DDR5 Tester")
		(date "2026-05-21")
		(rev "2.2.0")
		(company "Antmicro")
		(comment 9 "footprints 726-730 of 796")
	)
	(layers
		(0 "F.Cu" signal)
		(4 "In1.Cu" power)
		(6 "In2.Cu" mixed)
		(8 "In3.Cu" power)
		(10 "In4.Cu" mixed)
		(12 "In5.Cu" power)
		(14 "In6.Cu" mixed)
		(16 "In7.Cu" power)
		(18 "In8.Cu" power)
		(20 "In9.Cu" mixed)
		(22 "In10.Cu" power)
		(2 "B.Cu" signal)
		(9 "F.Adhes" user "F.Adhesive")
		(11 "B.Adhes" user "B.Adhesive")
		(13 "F.Paste" user)
		(15 "B.Paste" user)
		(5 "F.SilkS" user "F.Silkscreen")
		(7 "B.SilkS" user "B.Silkscreen")
		(1 "F.Mask" user)
		(3 "B.Mask" user)
		(17 "Dwgs.User" user "User.Drawings")
		(19 "Cmts.User" user "User.Comments")
		(21 "Eco1.User" user "User.Eco1")
		(23 "Eco2.User" user "User.Eco2")
		(25 "Edge.Cuts" user)
		(27 "Margin" user)
		(31 "F.CrtYd" user "F.Courtyard")
		(29 "B.CrtYd" user "B.Courtyard")
		(35 "F.Fab" user)
		(33 "B.Fab" user)
	)
	(footprint "antmicro-footprints:C_0603_1608Metric"
		(layer "B.Cu")
		(at 218.26 172.06 90)
		(descr "Capacitor SMD 0603")
		(tags "capacitor 0603")
		(property "Reference" "C270"
			(at -4.04 0.39 90)
			(layer "B.SilkS")
			(effects
				(font
					(size 0.7 0.7)
					(thickness 0.15)
				)
				(justify right bottom mirror)
			)
		)
		(property "Value" "C_22u_0603"
			(at -1.42757 -1.770288 90)
			(layer "B.Fab")
			(effects
				(font
					(size 0.7 0.7)
					(thickness 0.15)
				)
				(justify right bottom mirror)
			)
		)
		(property "Datasheet" "https://www.murata.com/products/productdetail?partno=GRM188R60J226MEA0%23"
			(at 0 0 90)
			(layer "F.Fab")
			(hide yes)
			(effects
				(font
					(size 1.27 1.27)
					(thickness 0.15)
				)
			)
		)
		(property "Manufacturer" "Murata"
			(at 0 0 90)
			(unlocked yes)
			(layer "B.Fab")
			(hide yes)
			(effects
				(font
					(size 1 1)
					(thickness 0.15)
				)
				(justify mirror)
			)
		)
		(property "MPN" "GRM188R60J226MEA0D"
			(at 0 0 90)
			(unlocked yes)
			(layer "B.Fab")
			(hide yes)
			(effects
				(font
					(size 1 1)
					(thickness 0.15)
				)
				(justify mirror)
			)
		)
		(property "Val" "22u"
			(at 0 0 90)
			(unlocked yes)
			(layer "B.Fab")
			(hide yes)
			(effects
				(font
					(size 1 1)
					(thickness 0.15)
				)
				(justify mirror)
			)
		)
		(property "License" "Apache-2.0"
			(at 0 0 90)
			(unlocked yes)
			(layer "B.Fab")
			(hide yes)
			(effects
				(font
					(size 1 1)
					(thickness 0.15)
				)
				(justify mirror)
			)
		)
		(property "Author" "Antmicro"
			(at 0 0 90)
			(unlocked yes)
			(layer "B.Fab")
			(hide yes)
			(effects
				(font
					(size 1 1)
					(thickness 0.15)
				)
				(justify mirror)
			)
		)
		(property "Voltage" ""
			(at 0 0 90)
			(unlocked yes)
			(layer "B.Fab")
			(hide yes)
			(effects
				(font
					(size 1 1)
					(thickness 0.15)
				)
				(justify mirror)
			)
		)
		(property "Dielectric" ""
			(at 0 0 90)
			(unlocked yes)
			(layer "B.Fab")
			(hide yes)
			(effects
				(font
					(size 1 1)
					(thickness 0.15)
				)
				(justify mirror)
			)
		)
		(sheetname "/Supply/DC-DC VCCINT/")
		(sheetfile "dc-dc-vccint.kicad_sch")
		(attr smd)
		(fp_line
			(start -0.15 -0.4)
			(end 0.15 -0.4)
			(stroke
				(width 0.15)
				(type solid)
			)
			(layer "B.SilkS")
		)
		(fp_line
			(start -0.15 0.4)
			(end 0.15 0.4)
			(stroke
				(width 0.15)
				(type solid)
			)
			(layer "B.SilkS")
		)
		(fp_rect
			(start -1.25 0.65)
			(end 1.25 -0.65)
			(stroke
				(width 0.05)
				(type solid)
			)
			(fill no)
			(layer "B.CrtYd")
		)
		(fp_rect
			(start -0.8 0.4)
			(end 0.8 -0.4)
			(stroke
				(width 0.15)
				(type solid)
			)
			(fill no)
			(layer "B.Fab")
		)
		(fp_text user "${REFERENCE}"
			(at -1.682 -3.895 270)
			(layer "B.Fab")
			(effects
				(font
					(size 0.7 0.7)
					(thickness 0.15)
				)
				(justify left bottom mirror)
			)
		)
		(fp_text user "Author: Antmicro"
			(at -1.682 -4.894 270)
			(layer "B.Fab")
			(effects
				(font
					(size 0.7 0.7)
					(thickness 0.15)
				)
				(justify left bottom mirror)
			)
		)
		(fp_text user "License: Apache-2.0"
			(at -1.682 -5.895 270)
			(layer "B.Fab")
			(effects
				(font
					(size 0.7 0.7)
					(thickness 0.15)
				)
				(justify left bottom mirror)
			)
		)
		(pad "1" smd roundrect
			(at -0.7 0 90)
			(size 0.8 1)
			(layers "B.Cu" "B.Mask" "B.Paste")
			(roundrect_rratio 0.2)
			(net 1 "GND")
			(pintype "passive")
		)
		(pad "2" smd roundrect
			(at 0.7 0 90)
			(size 0.8 1)
			(layers "B.Cu" "B.Mask" "B.Paste")
			(roundrect_rratio 0.2)
			(net 223 "/Supply/DC-DC VCCINT/0V85_REG0")
			(pintype "passive")
		)
	)
	(footprint "antmicro-footprints:C_0603_1608Metric"
		(layer "B.Cu")
		(at 227.435 172.06 90)
		(descr "Capacitor SMD 0603")
		(tags "capacitor 0603")
		(property "Reference" "C249"
			(at -4.069998 0.320001 90)
			(layer "B.SilkS")
			(effects
				(font
					(size 0.7 0.7)
					(thickness 0.15)
				)
				(justify right bottom mirror)
			)
		)
		(property "Value" "C_22u_0603"
			(at -1.42757 -1.770288 90)
			(layer "B.Fab")
			(effects
				(font
					(size 0.7 0.7)
					(thickness 0.15)
				)
				(justify right bottom mirror)
			)
		)
		(property "Datasheet" "https://www.murata.com/products/productdetail?partno=GRM188R60J226MEA0%23"
			(at 0 0 90)
			(layer "F.Fab")
			(hide yes)
			(effects
				(font
					(size 1.27 1.27)
					(thickness 0.15)
				)
			)
		)
		(property "Manufacturer" "Murata"
			(at 0 0 90)
			(unlocked yes)
			(layer "B.Fab")
			(hide yes)
			(effects
				(font
					(size 1 1)
					(thickness 0.15)
				)
				(justify mirror)
			)
		)
		(property "MPN" "GRM188R60J226MEA0D"
			(at 0 0 90)
			(unlocked yes)
			(layer "B.Fab")
			(hide yes)
			(effects
				(font
					(size 1 1)
					(thickness 0.15)
				)
				(justify mirror)
			)
		)
		(property "Val" "22u"
			(at 0 0 90)
			(unlocked yes)
			(layer "B.Fab")
			(hide yes)
			(effects
				(font
					(size 1 1)
					(thickness 0.15)
				)
				(justify mirror)
			)
		)
		(property "License" "Apache-2.0"
			(at 0 0 90)
			(unlocked yes)
			(layer "B.Fab")
			(hide yes)
			(effects
				(font
					(size 1 1)
					(thickness 0.15)
				)
				(justify mirror)
			)
		)
		(property "Author" "Antmicro"
			(at 0 0 90)
			(unlocked yes)
			(layer "B.Fab")
			(hide yes)
			(effects
				(font
					(size 1 1)
					(thickness 0.15)
				)
				(justify mirror)
			)
		)
		(property "Voltage" ""
			(at 0 0 90)
			(unlocked yes)
			(layer "B.Fab")
			(hide yes)
			(effects
				(font
					(size 1 1)
					(thickness 0.15)
				)
				(justify mirror)
			)
		)
		(property "Dielectric" ""
			(at 0 0 90)
			(unlocked yes)
			(layer "B.Fab")
			(hide yes)
			(effects
				(font
					(size 1 1)
					(thickness 0.15)
				)
				(justify mirror)
			)
		)
		(sheetname "/Supply/DC-DC VCCINT/")
		(sheetfile "dc-dc-vccint.kicad_sch")
		(attr smd)
		(fp_line
			(start -0.15 -0.4)
			(end 0.15 -0.4)
			(stroke
				(width 0.15)
				(type solid)
			)
			(layer "B.SilkS")
		)
		(fp_line
			(start -0.15 0.4)
			(end 0.15 0.4)
			(stroke
				(width 0.15)
				(type solid)
			)
			(layer "B.SilkS")
		)
		(fp_rect
			(start -1.25 0.65)
			(end 1.25 -0.65)
			(stroke
				(width 0.05)
				(type solid)
			)
			(fill no)
			(layer "B.CrtYd")
		)
		(fp_rect
			(start -0.8 0.4)
			(end 0.8 -0.4)
			(stroke
				(width 0.15)
				(type solid)
			)
			(fill no)
			(layer "B.Fab")
		)
		(fp_text user "Author: Antmicro"
			(at -1.682 -4.894 270)
			(layer "B.Fab")
			(effects
				(font
					(size 0.7 0.7)
					(thickness 0.15)
				)
				(justify left bottom mirror)
			)
		)
		(fp_text user "${REFERENCE}"
			(at -1.682 -3.895 270)
			(layer "B.Fab")
			(effects
				(font
					(size 0.7 0.7)
					(thickness 0.15)
				)
				(justify left bottom mirror)
			)
		)
		(fp_text user "License: Apache-2.0"
			(at -1.682 -5.895 270)
			(layer "B.Fab")
			(effects
				(font
					(size 0.7 0.7)
					(thickness 0.15)
				)
				(justify left bottom mirror)
			)
		)
		(pad "1" smd roundrect
			(at -0.7 0 90)
			(size 0.8 1)
			(layers "B.Cu" "B.Mask" "B.Paste")
			(roundrect_rratio 0.2)
			(net 1 "GND")
			(pintype "passive")
		)
		(pad "2" smd roundrect
			(at 0.7 0 90)
			(size 0.8 1)
			(layers "B.Cu" "B.Mask" "B.Paste")
			(roundrect_rratio 0.2)
			(net 224 "/Supply/DC-DC VCCINT/0V85_REG1")
			(pintype "passive")
		)
	)
	(footprint "antmicro-footprints:C_0402_1005Metric"
		(layer "B.Cu")
		(at 119.91 125.802383 90)
		(descr "Capacitor SMD 0402")
		(tags "capacitor SMD 0402")
		(property "Reference" "C135"
			(at 1.151513 -0.318604 90)
			(layer "B.SilkS")
			(effects
				(font
					(size 0.7 0.7)
					(thickness 0.15)
				)
				(justify right top mirror)
			)
		)
		(property "Value" "C_100n_0402"
			(at -1.022927 -2.155213 90)
			(layer "B.Fab")
			(effects
				(font
					(size 0.7 0.7)
					(thickness 0.15)
				)
				(justify right top mirror)
			)
		)
		(property "Datasheet" "https://www.murata.com/products/productdetail?partno=GRM155R61H104KE14%23"
			(at 0 0 90)
			(layer "F.Fab")
			(hide yes)
			(effects
				(font
					(size 1.27 1.27)
					(thickness 0.15)
				)
			)
		)
		(property "MPN" "GRM155R61H104KE14D"
			(at 0 0 90)
			(unlocked yes)
			(layer "B.Fab")
			(hide yes)
			(effects
				(font
					(size 1 1)
					(thickness 0.15)
				)
				(justify mirror)
			)
		)
		(property "Manufacturer" "Murata"
			(at 0 0 90)
			(unlocked yes)
			(layer "B.Fab")
			(hide yes)
			(effects
				(font
					(size 1 1)
					(thickness 0.15)
				)
				(justify mirror)
			)
		)
		(property "License" "Apache-2.0"
			(at 0 0 90)
			(unlocked yes)
			(layer "B.Fab")
			(hide yes)
			(effects
				(font
					(size 1 1)
					(thickness 0.15)
				)
				(justify mirror)
			)
		)
		(property "Author" "Antmicro"
			(at 0 0 90)
			(unlocked yes)
			(layer "B.Fab")
			(hide yes)
			(effects
				(font
					(size 1 1)
					(thickness 0.15)
				)
				(justify mirror)
			)
		)
		(property "Val" "100n"
			(at 0 0 90)
			(unlocked yes)
			(layer "B.Fab")
			(hide yes)
			(effects
				(font
					(size 1 1)
					(thickness 0.15)
				)
				(justify mirror)
			)
		)
		(property "Voltage" "50V"
			(at 0 0 90)
			(unlocked yes)
			(layer "B.Fab")
			(hide yes)
			(effects
				(font
					(size 1 1)
					(thickness 0.15)
				)
				(justify mirror)
			)
		)
		(property "Dielectric" "X5R"
			(at 0 0 90)
			(unlocked yes)
			(layer "B.Fab")
			(hide yes)
			(effects
				(font
					(size 1 1)
					(thickness 0.15)
				)
				(justify mirror)
			)
		)
		(sheetname "/Ethernet/")
		(sheetfile "ethernet.kicad_sch")
		(attr smd)
		(fp_rect
			(start -0.925 0.47)
			(end 0.925 -0.47)
			(stroke
				(width 0.05)
				(type default)
			)
			(fill no)
			(layer "B.CrtYd")
		)
		(fp_line
			(start 0.504 -0.248)
			(end -0.494 -0.248)
			(stroke
				(width 0.15)
				(type solid)
			)
			(layer "B.Fab")
		)
		(fp_line
			(start -0.494 -0.248)
			(end -0.494 0.25)
			(stroke
				(width 0.15)
				(type solid)
			)
			(layer "B.Fab")
		)
		(fp_line
			(start 0.504 0.25)
			(end 0.504 -0.248)
			(stroke
				(width 0.15)
				(type solid)
			)
			(layer "B.Fab")
		)
		(fp_line
			(start -0.494 0.25)
			(end 0.504 0.25)
			(stroke
				(width 0.15)
				(type solid)
			)
			(layer "B.Fab")
		)
		(fp_text user "Author: Antmicro"
			(at -0.939 -3.399 270)
			(layer "B.Fab")
			(effects
				(font
					(size 0.7 0.7)
					(thickness 0.15)
				)
				(justify left bottom mirror)
			)
		)
		(fp_text user "${REFERENCE}"
			(at -0.939 -4.599 270)
			(layer "B.Fab")
			(effects
				(font
					(size 0.7 0.7)
					(thickness 0.15)
				)
				(justify left bottom mirror)
			)
		)
		(fp_text user "License: Apache-2.0"
			(at -0.939 -5.799 270)
			(layer "B.Fab")
			(effects
				(font
					(size 0.7 0.7)
					(thickness 0.15)
				)
				(justify left bottom mirror)
			)
		)
		(pad "1" smd roundrect
			(at -0.48 0 90)
			(size 0.59 0.64)
			(layers "B.Cu" "B.Mask" "B.Paste")
			(roundrect_rratio 0.25)
			(net 1 "GND")
			(pintype "passive")
		)
		(pad "2" smd roundrect
			(at 0.48 0 90)
			(size 0.59 0.64)
			(layers "B.Cu" "B.Mask" "B.Paste")
			(roundrect_rratio 0.25)
			(net 821 "Net-(C135-Pad2)")
			(pintype "passive")
		)
	)
	(footprint "antmicro-footprints:R_0402_1005Metric_EIA"
		(layer "B.Cu")
		(at 181.499 149)
		(descr "Resistor SMD 0402 (1005 Metric), square (rectangular) end terminal, IPC_7351 nominal, (Body size source: IPC-SM-782 page 76, https://www.pcb-3d.com/wordpress/wp-content/uploads/ipc-sm-782a_amendment_1_and_2.pdf)")
		(tags "resistor 0402")
		(property "Reference" "R132"
			(at -1.899 -1.4 0)
			(layer "B.SilkS")
			(effects
				(font
					(size 0.7 0.7)
					(thickness 0.15)
				)
				(justify right top mirror)
			)
		)
		(property "Value" "R_1k_0402"
			(at 0 -1.169 0)
			(layer "B.Fab")
			(effects
				(font
					(size 0.7 0.7)
					(thickness 0.15)
				)
				(justify right top mirror)
			)
		)
		(property "Datasheet" "https://www.bourns.com/docs/product-datasheets/cr.pdf"
			(at 0 0 0)
			(layer "F.Fab")
			(hide yes)
			(effects
				(font
					(size 1.27 1.27)
					(thickness 0.15)
				)
			)
		)
		(property "MPN" "CR0402-FX-1001GLF"
			(at 0 0 0)
			(unlocked yes)
			(layer "B.Fab")
			(hide yes)
			(effects
				(font
					(size 1 1)
					(thickness 0.15)
				)
				(justify mirror)
			)
		)
		(property "Manufacturer" "Bourns"
			(at 0 0 0)
			(unlocked yes)
			(layer "B.Fab")
			(hide yes)
			(effects
				(font
					(size 1 1)
					(thickness 0.15)
				)
				(justify mirror)
			)
		)
		(property "License" "Apache-2.0"
			(at 0 0 0)
			(unlocked yes)
			(layer "B.Fab")
			(hide yes)
			(effects
				(font
					(size 1 1)
					(thickness 0.15)
				)
				(justify mirror)
			)
		)
		(property "Author" "Antmicro"
			(at 0 0 0)
			(unlocked yes)
			(layer "B.Fab")
			(hide yes)
			(effects
				(font
					(size 1 1)
					(thickness 0.15)
				)
				(justify mirror)
			)
		)
		(property "Val" "1k"
			(at 0 0 0)
			(unlocked yes)
			(layer "B.Fab")
			(hide yes)
			(effects
				(font
					(size 1 1)
					(thickness 0.15)
				)
				(justify mirror)
			)
		)
		(property "Tolerance" "1%"
			(at 0 0 0)
			(unlocked yes)
			(layer "B.Fab")
			(hide yes)
			(effects
				(font
					(size 1 1)
					(thickness 0.15)
				)
				(justify mirror)
			)
		)
		(sheetname "/FPGA banks HP/")
		(sheetfile "fpga-hp-banks.kicad_sch")
		(attr smd exclude_from_bom dnp)
		(fp_rect
			(start -0.95 0.45)
			(end 0.95 -0.45)
			(stroke
				(width 0.05)
				(type default)
			)
			(fill no)
			(layer "B.CrtYd")
		)
		(fp_line
			(start -0.5 -0.249)
			(end -0.5 0.25)
			(stroke
				(width 0.15)
				(type solid)
			)
			(layer "B.Fab")
		)
		(fp_line
			(start -0.5 0.25)
			(end 0.499 0.25)
			(stroke
				(width 0.15)
				(type solid)
			)
			(layer "B.Fab")
		)
		(fp_line
			(start 0.499 -0.249)
			(end -0.5 -0.249)
			(stroke
				(width 0.15)
				(type solid)
			)
			(layer "B.Fab")
		)
		(fp_line
			(start 0.499 0.25)
			(end 0.499 -0.249)
			(stroke
				(width 0.15)
				(type solid)
			)
			(layer "B.Fab")
		)
		(fp_text user "License: Apache-2.0"
			(at -0.95 -4.369 0)
			(layer "B.Fab")
			(effects
				(font
					(size 0.7 0.7)
					(thickness 0.15)
				)
				(justify right top mirror)
			)
		)
		(fp_text user "Author: Antmicro"
			(at -0.95 -5.569 0)
			(layer "B.Fab")
			(effects
				(font
					(size 0.7 0.7)
					(thickness 0.15)
				)
				(justify right top mirror)
			)
		)
		(fp_text user "${REFERENCE}"
			(at -0.95 -3.169 0)
			(layer "B.Fab")
			(effects
				(font
					(size 0.7 0.7)
					(thickness 0.15)
				)
				(justify right top mirror)
			)
		)
		(pad "1" smd roundrect
			(at -0.5 0 270)
			(size 0.6 0.6)
			(layers "B.Cu" "B.Mask" "B.Paste")
			(roundrect_rratio 0.25)
			(net 1 "GND")
			(pintype "passive")
		)
		(pad "2" smd roundrect
			(at 0.499 0)
			(size 0.6 0.6)
			(layers "B.Cu" "B.Mask" "B.Paste")
			(roundrect_rratio 0.25)
			(net 546 "/FPGA banks HP/VREF_67")
			(pintype "passive")
		)
	)
	(footprint "antmicro-footprints:R_0402_1005Metric"
		(layer "B.Cu")
		(at 236.22 154.262 90)
		(descr "Resistor SMD 0402")
		(tags "resistor SMD 0402")
		(property "Reference" "R214"
			(at 1.062 0.38 90)
			(layer "B.SilkS")
			(effects
				(font
					(size 0.7 0.7)
					(thickness 0.15)
				)
				(justify right bottom mirror)
			)
		)
		(property "Value" "R_0R_0402"
			(at -1.011843 -1.772047 90)
			(layer "B.Fab")
			(effects
				(font
					(size 0.7 0.7)
					(thickness 0.15)
				)
				(justify right bottom mirror)
			)
		)
		(property "Datasheet" "https://industrial.panasonic.com/cdbs/www-data/pdf/RDA0000/AOA0000C301.pdf"
			(at 0 0 90)
			(layer "F.Fab")
			(hide yes)
			(effects
				(font
					(size 1.27 1.27)
					(thickness 0.15)
				)
			)
		)
		(property "MPN" "ERJ2GE0R00X"
			(at 0 0 90)
			(unlocked yes)
			(layer "B.Fab")
			(hide yes)
			(effects
				(font
					(size 1 1)
					(thickness 0.15)
				)
				(justify mirror)
			)
		)
		(property "Manufacturer" "Panasonic"
			(at 0 0 90)
			(unlocked yes)
			(layer "B.Fab")
			(hide yes)
			(effects
				(font
					(size 1 1)
					(thickness 0.15)
				)
				(justify mirror)
			)
		)
		(property "License" "Apache-2.0"
			(at 0 0 90)
			(unlocked yes)
			(layer "B.Fab")
			(hide yes)
			(effects
				(font
					(size 1 1)
					(thickness 0.15)
				)
				(justify mirror)
			)
		)
		(property "Author" "Antmicro"
			(at 0 0 90)
			(unlocked yes)
			(layer "B.Fab")
			(hide yes)
			(effects
				(font
					(size 1 1)
					(thickness 0.15)
				)
				(justify mirror)
			)
		)
		(property "Val" "0R"
			(at 0 0 90)
			(unlocked yes)
			(layer "B.Fab")
			(hide yes)
			(effects
				(font
					(size 1 1)
					(thickness 0.15)
				)
				(justify mirror)
			)
		)
		(property "Tolerance" "~"
			(at 0 0 90)
			(unlocked yes)
			(layer "B.Fab")
			(hide yes)
			(effects
				(font
					(size 1 1)
					(thickness 0.15)
				)
				(justify mirror)
			)
		)
		(property "Current" "1A"
			(at 0 0 90)
			(unlocked yes)
			(layer "B.Fab")
			(hide yes)
			(effects
				(font
					(size 1 1)
					(thickness 0.15)
				)
				(justify mirror)
			)
		)
		(sheetname "/Supply/DC-DC IO/")
		(sheetfile "dc-dc-io.kicad_sch")
		(attr smd)
		(fp_rect
			(start -0.925 0.47)
			(end 0.925 -0.47)
			(stroke
				(width 0.05)
				(type default)
			)
			(fill no)
			(layer "B.CrtYd")
		)
		(fp_rect
			(start -0.5 0.25)
			(end 0.5 -0.25)
			(stroke
				(width 0.15)
				(type solid)
			)
			(fill no)
			(layer "B.Fab")
		)
		(fp_text user "License: Apache-2.0"
			(at -0.95 -5.169 270)
			(layer "B.Fab")
			(effects
				(font
					(size 0.7 0.7)
					(thickness 0.15)
				)
				(justify left bottom mirror)
			)
		)
		(fp_text user "Author: Antmicro"
			(at -0.95 -4.169 270)
			(layer "B.Fab")
			(effects
				(font
					(size 0.7 0.7)
					(thickness 0.15)
				)
				(justify left bottom mirror)
			)
		)
		(fp_text user "${REFERENCE}"
			(at -0.95 -3.168 270)
			(layer "B.Fab")
			(effects
				(font
					(size 0.7 0.7)
					(thickness 0.15)
				)
				(justify left bottom mirror)
			)
		)
		(pad "1" smd roundrect
			(at -0.48 0 90)
			(size 0.59 0.64)
			(layers "B.Cu" "B.Mask" "B.Paste")
			(roundrect_rratio 0.25)
			(net 734 "Net-(U28-IN4+)")
			(pintype "passive")
		)
		(pad "2" smd roundrect
			(at 0.48 0 90)
			(size 0.59 0.64)
			(layers "B.Cu" "B.Mask" "B.Paste")
			(roundrect_rratio 0.25)
			(net 688 "/Supply/DC-DC IO/1V2_SEN_+")
			(pintype "passive")
		)
	)
)
